# S9S_MB_2U (Grand Teton) — schematic netlist excerpt (pin names and nets, part order shuffled) for the footprints in the layout excerpt that follows; sources: Cadence DE-HDL packaged netlist, KiCad conversion of 03242023_DA0F0TMBIJ0_F0T_Motherboard_J_brd_V01_OCP.brd

C274  Q_CAP  22UF 4V 20% X6S  pkg C0402  page 77 : A = PVCCIN_CPU1 ; B = GND

(kicad_pcb
	(version 20260206)
	(generator "pcbnew")
	(generator_version "10.0")
	(general
		(thickness 1.6)
		(legacy_teardrops no)
	)
	(paper "A4")
	(title_block
		(title "03242023_DA0F0TMBIJ0_F0T_Motherboard_J_brd_V01_OCP.brd")
		(comment 1 "Grand Teton / footprints 36-36 of 6105")
	)
	(layers
		(0 "F.Cu" signal "TOP")
		(4 "In1.Cu" signal "GND")
		(6 "In2.Cu" signal "IN1")
		(8 "In3.Cu" signal "GND1")
		(10 "In4.Cu" signal "IN2")
		(12 "In5.Cu" signal "GND2")
		(14 "In6.Cu" signal "IN3")
		(16 "In7.Cu" signal "GND3")
		(18 "In8.Cu" signal "VCC")
		(20 "In9.Cu" signal "VCC1")
		(22 "In10.Cu" signal "GND4")
		(24 "In11.Cu" signal "IN4")
		(26 "In12.Cu" signal "GND5")
		(28 "In13.Cu" signal "IN5")
		(30 "In14.Cu" signal "GND6")
		(32 "In15.Cu" signal "IN6")
		(34 "In16.Cu" signal "GND7")
		(2 "B.Cu" signal "BOTTOM")
		(9 "F.Adhes" user "F.Adhesive")
		(11 "B.Adhes" user "B.Adhesive")
		(13 "F.Paste" user "Package Geometry/Pastemask Top")
		(15 "B.Paste" user "Package Geometry/Pastemask Bottom")
		(5 "F.SilkS" user "Ref Des/Silkscreen Top")
		(7 "B.SilkS" user "Ref Des/Silkscreen Bottom")
		(1 "F.Mask" user "Board Geometry/Soldermask Top")
		(3 "B.Mask" user "Board Geometry/Soldermask Bottom")
		(17 "Dwgs.User" user "User.Drawings")
		(19 "Cmts.User" user "User.Comments")
		(21 "Eco1.User" user "User.Eco1")
		(23 "Eco2.User" user "User.Eco2")
		(25 "Edge.Cuts" user "Board Geometry/Outline")
		(27 "Margin" user)
		(31 "F.CrtYd" user "Package Geometry/Place Bound Top")
		(29 "B.CrtYd" user "Package Geometry/Place Bound Bottom")
		(35 "F.Fab" user "Ref Des/Assembly Top")
		(33 "B.Fab" user "Ref Des/Assembly Bottom")
	)
	(footprint ""
		(layer "F.Cu")
		(at 117.526816 -244.032024 90)
		(property "Reference" "C274"
			(at 0 0 90)
			(layer "F.SilkS")
			(hide yes)
			(effects
				(font
					(size 1.27 1.27)
				)
			)
		)
		(property "Value" ""
			(at 0 0 90)
			(layer "F.Fab")
			(effects
				(font
					(size 1.27 1.27)
				)
			)
		)
		(duplicate_pad_numbers_are_jumpers no)
		(fp_line
			(start 0.7874 -0.4064)
			(end 0.7874 0.4064)
			(stroke
				(width 0.1524)
				(type default)
			)
			(layer "F.SilkS")
		)
		(fp_line
			(start -0.7874 -0.4064)
			(end 0.7874 -0.4064)
			(stroke
				(width 0.1524)
				(type default)
			)
			(layer "F.SilkS")
		)
		(fp_line
			(start 0.7874 0.4064)
			(end -0.7874 0.4064)
			(stroke
				(width 0.1524)
				(type default)
			)
			(layer "F.SilkS")
		)
		(fp_line
			(start -0.7874 0.4064)
			(end -0.7874 -0.4064)
			(stroke
				(width 0.1524)
				(type default)
			)
			(layer "F.SilkS")
		)
		(fp_line
			(start -0.12065 -0.305054)
			(end -0.12065 -0.2794)
			(stroke
				(width 0.1)
				(type default)
			)
			(layer "F.Fab")
		)
		(fp_line
			(start -0.67945 -0.305054)
			(end -0.12065 -0.305054)
			(stroke
				(width 0.1)
				(type default)
			)
			(layer "F.Fab")
		)
		(fp_line
			(start 0.67945 -0.3048)
			(end 0.67945 0.3048)
			(stroke
				(width 0.1)
				(type default)
			)
			(layer "F.Fab")
		)
		(fp_line
			(start 0.12065 -0.3048)
			(end 0.67945 -0.3048)
			(stroke
				(width 0.1)
				(type default)
			)
			(layer "F.Fab")
		)
		(fp_line
			(start 0.12065 -0.2794)
			(end 0.12065 -0.3048)
			(stroke
				(width 0.1)
				(type default)
			)
			(layer "F.Fab")
		)
		(fp_line
			(start -0.12065 -0.2794)
			(end 0.12065 -0.2794)
			(stroke
				(width 0.1)
				(type default)
			)
			(layer "F.Fab")
		)
		(fp_line
			(start 0.120396 0.2794)
			(end -0.12065 0.2794)
			(stroke
				(width 0.1)
				(type default)
			)
			(layer "F.Fab")
		)
		(fp_line
			(start -0.12065 0.2794)
			(end -0.12065 0.3048)
			(stroke
				(width 0.1)
				(type default)
			)
			(layer "F.Fab")
		)
		(fp_line
			(start 0.67945 0.3048)
			(end 0.120396 0.3048)
			(stroke
				(width 0.1)
				(type default)
			)
			(layer "F.Fab")
		)
		(fp_line
			(start 0.120396 0.3048)
			(end 0.120396 0.2794)
			(stroke
				(width 0.1)
				(type default)
			)
			(layer "F.Fab")
		)
		(fp_line
			(start -0.12065 0.3048)
			(end -0.67945 0.3048)
			(stroke
				(width 0.1)
				(type default)
			)
			(layer "F.Fab")
		)
		(fp_line
			(start -0.67945 0.3048)
			(end -0.67945 -0.305054)
			(stroke
				(width 0.1)
				(type default)
			)
			(layer "F.Fab")
		)
		(pad "1" smd circle
			(at -0.40005 0 90)
			(size 0 0)
			(layers "F.Cu" "F.Mask" "F.Paste")
			(net "PVCCIN_CPU1")
		)
		(pad "2" smd circle
			(at 0.40005 0 90)
			(size 0 0)
			(layers "F.Cu" "F.Mask" "F.Paste")
			(net "GND")
		)
	)
)
